DEVICE-TYPE           GERBER_RS274X
OUTPUT-UNITS          INCHES
FILM-SIZE             3600000 2400000
FORMAT                2.5
ABORT-ON-ERROR        NO
SCALE                 1
SUPPRESS-LEAD-ZEROES  YES
SUPPRESS-TRAIL-ZEROES NO
SUPPRESS-EQUAL        YES
UNDEF-APT-CONT        NO
